FILE_TYPE = MACRO_DRAWING;
SET COLOR_WIRE YELLOW;
SET COLOR_PROP ORANGE;
SET COLOR_DOT WHITE;
SET COLOR_ARC YELLOW;
SET COLOR_BODY GREEN;
SET COLOR_NOTE PURPLE;
SET PROP_DISPLAY VALUE;
SET PAGE_NUMBER P1;
FORCEADD QUANTA_TITLE_BLOCK_C..1
(-100 100);
FORCEPROP 1 LAST CUSTOM_TXT_CDS <NAME_2>
J 0
(-3275 150);
FORCEPROP 1 LAST CUSTOM_TXT_CDS <NAME_1>
J 0
(-3275 275);
FORCEPROP 1 LAST CUSTOM_TXT_CDS <Q_NUMBER>
J 0
(-1503 203);
DISPLAY 1.212766 (-1503 203);
FORCEPROP 1 LAST CUSTOM_TXT_CDS <Q_PROJ>
J 0
(-2482 202);
DISPLAY 1.212766 (-2482 202);
FORCEPROP 1 LAST CUSTOM_TXT_CDS <Q_REV>
J 0
(-284 203);
DISPLAY 1.212766 (-284 203);
FORCEPROP 1 LAST CUSTOM_TXT_CDS <CON_LAST_MODIFIED>
J 0
(-1985 115);
DISPLAY 0.978723 (-1985 115);
FORCEPROP 1 LAST CUSTOM_TXT_CDS <CON_PAGE_NUM> OF <CON_TOTAL_PAGES>
J 0
(-546 118);
DISPLAY 0.978723 (-546 118);
FORCEPROP 1 LAST Q_TITLE COVER PAGE
J 0
(-9400 150);
DISPLAY 2.446809 (-9400 150);
PAINT GREEN (-9400 150);
FORCEPROP 0 LAST CDS_CON_LAST_MODIFIED Wed Sep 13 22:10:40 2023
J 0
(-1985 115);
DISPLAY INVISIBLE (-1985 115);
FORCEPROP 2 LAST CUSTOM_TXT_CDS <XR_PAGE_TITLE>
J 0
(-7990 5350);
DISPLAY 0.638298 (-7990 5350);
PAINT PINK (-7990 5350);
DISPLAY INVISIBLE (-7990 5350);
FORCEPROP 1 LAST Q_DEPT BU9
J 1
(-3850 175);
DISPLAY 1.957447 (-3850 175);
PAINT GREEN (-3850 175);
DISPLAY INVISIBLE (-3850 175);
FORCEPROP 1 LAST COMMENT_BODY TRUE
J 0
(-88 87);
DISPLAY 0.978723 (-88 87);
PAINT GREEN (-88 87);
DISPLAY INVISIBLE (-88 87);
FORCEPROP 2 LAST CDS_LIB pure_quanta
J 0
(-100 100);
DISPLAY INVISIBLE (-100 100);
FORCEPROP 1 LAST CDS_LMAN_SYM_OUTLINE -9475,6775,100,-125
J 0
(-100 100);
DISPLAY 0.468085 (-100 100);
PAINT GREEN (-100 100);
DISPLAY INVISIBLE (-100 100);
FORCEPROP 2 LAST PAGE_BORDER TRUE
J 0
(-7990 5350);
DISPLAY 0.638298 (-7990 5350);
PAINT PINK (-7990 5350);
DISPLAY INVISIBLE (-7990 5350);
FORCEPROP 2 LAST CDS_XR_PAGE_TITLE CR-1 : @T6G_MB_LIB.T6G(SCH_1):PAGE1
J 0
(-7990 5350);
DISPLAY 0.638298 (-7990 5350);
PAINT PINK (-7990 5350);
DISPLAY INVISIBLE (-7990 5350);
FORCENOTE
PROJECT NAME:GT AMD
(-7425 3025) 0;
DISPLAY LEFT (-7425 3025);
DISPLAY 4.872340 (-7425 3025);
PAINT WHITE (-7425 3025);
FORCENOTE
8 RETIMER
(-5950 3700) 0;
DISPLAY LEFT (-5950 3700);
DISPLAY 6.148936 (-5950 3700);
PAINT RED (-5950 3700);
FORCENOTE
GT AMD MB
(-7325 4425) 0;
DISPLAY LEFT (-7325 4425);
DISPLAY 12.000000 (-7325 4425);
PAINT WHITE (-7325 4425);
FORCENOTE
REV:C
(-7425 2650) 0;
DISPLAY LEFT (-7425 2650);
DISPLAY 4.872340 (-7425 2650);
PAINT WHITE (-7425 2650);
FORCENOTE
REV:V02
(-7400 1575) 0;
DISPLAY LEFT (-7400 1575);
DISPLAY 4.872340 (-7400 1575);
PAINT WHITE (-7400 1575);
FORCENOTE
DATE:2023/07/13
(-7425 1900) 0;
DISPLAY LEFT (-7425 1900);
DISPLAY 4.872340 (-7425 1900);
PAINT WHITE (-7425 1900);
FORCENOTE
PCBA:
(-7425 2275) 0;
DISPLAY LEFT (-7425 2275);
DISPLAY 4.872340 (-7425 2275);
PAINT WHITE (-7425 2275);
QUIT
